# T6G (Grand Teton) — schematic netlist excerpt (pin names and nets, part order shuffled) for the footprints in the layout excerpt that follows; sources: Cadence DE-HDL packaged netlist, KiCad conversion of 04192023_DAF0TMB3IC0_F0TG_MB_C_brd_V02_OCP.brd

R1101  Q_RES  1K 1% EMPTY  pkg 0201LF  page 309 : A = P1V8_CPU0_RT_1D ; B = RT_CPU0_P3_ADDR1
C1236  Q_CAP  0.1UF 25V 10% X7R  pkg 0402  page 131 : A = P12V_OCP_SFF_R ; B = GND
R66  Q_RES  2.2K 5% CHIP  pkg 0402LF  page 250 : A = P3V3_AUX ; B = SMB_FRU_3V3AUX_SCL

(kicad_pcb
	(version 20260206)
	(generator "pcbnew")
	(generator_version "10.0")
	(general
		(thickness 1.6)
		(legacy_teardrops no)
	)
	(paper "A4")
	(title_block
		(title "04192023_DAF0TMB3IC0_F0TG_MB_C_brd_V02_OCP.brd")
		(comment 1 "Grand Teton / footprints 3011-3013 of 8354")
	)
	(layers
		(0 "F.Cu" signal "TOP")
		(4 "In1.Cu" signal "GND")
		(6 "In2.Cu" signal "IN1")
		(8 "In3.Cu" signal "GND1")
		(10 "In4.Cu" signal "IN2")
		(12 "In5.Cu" signal "GND2")
		(14 "In6.Cu" signal "IN3")
		(16 "In7.Cu" signal "GND3")
		(18 "In8.Cu" signal "VCC")
		(20 "In9.Cu" signal "VCC1")
		(22 "In10.Cu" signal "GND4")
		(24 "In11.Cu" signal "IN4")
		(26 "In12.Cu" signal "GND5")
		(28 "In13.Cu" signal "IN5")
		(30 "In14.Cu" signal "GND6")
		(32 "In15.Cu" signal "IN6")
		(34 "In16.Cu" signal "GND7")
		(2 "B.Cu" signal "BOTTOM")
		(9 "F.Adhes" user "F.Adhesive")
		(11 "B.Adhes" user "B.Adhesive")
		(13 "F.Paste" user "Package Geometry/Pastemask Top")
		(15 "B.Paste" user "Package Geometry/Pastemask Bottom")
		(5 "F.SilkS" user "Ref Des/Silkscreen Top")
		(7 "B.SilkS" user "Ref Des/Silkscreen Bottom")
		(1 "F.Mask" user "Board Geometry/Soldermask Top")
		(3 "B.Mask" user "Board Geometry/Soldermask Bottom")
		(17 "Dwgs.User" user "User.Drawings")
		(19 "Cmts.User" user "User.Comments")
		(21 "Eco1.User" user "User.Eco1")
		(23 "Eco2.User" user "User.Eco2")
		(25 "Edge.Cuts" user "Board Geometry/Outline")
		(27 "Margin" user)
		(31 "F.CrtYd" user "Package Geometry/Place Bound Top")
		(29 "B.CrtYd" user "Package Geometry/Place Bound Bottom")
		(35 "F.Fab" user "Ref Des/Assembly Top")
		(33 "B.Fab" user "Ref Des/Assembly Bottom")
	)
	(footprint ""
		(layer "F.Cu")
		(at 297.486324 -116.545614 180)
		(property "Reference" "R66"
			(at 0 0 180)
			(layer "F.SilkS")
			(hide yes)
			(effects
				(font
					(size 1.27 1.27)
				)
			)
		)
		(property "Value" ""
			(at 0 0 180)
			(layer "F.Fab")
			(effects
				(font
					(size 1.27 1.27)
				)
			)
		)
		(duplicate_pad_numbers_are_jumpers no)
		(fp_line
			(start 0.7874 0.4064)
			(end -0.7874 0.4064)
			(stroke
				(width 0.1524)
				(type default)
			)
			(layer "F.SilkS")
		)
		(fp_line
			(start 0.7874 -0.4064)
			(end 0.7874 0.4064)
			(stroke
				(width 0.1524)
				(type default)
			)
			(layer "F.SilkS")
		)
		(fp_line
			(start -0.7874 0.4064)
			(end -0.7874 -0.4064)
			(stroke
				(width 0.1524)
				(type default)
			)
			(layer "F.SilkS")
		)
		(fp_line
			(start -0.7874 -0.4064)
			(end 0.7874 -0.4064)
			(stroke
				(width 0.1524)
				(type default)
			)
			(layer "F.SilkS")
		)
		(fp_line
			(start 0.67945 0.3048)
			(end 0.120396 0.3048)
			(stroke
				(width 0.1)
				(type default)
			)
			(layer "F.Fab")
		)
		(fp_line
			(start 0.67945 -0.3048)
			(end 0.67945 0.3048)
			(stroke
				(width 0.1)
				(type default)
			)
			(layer "F.Fab")
		)
		(fp_line
			(start 0.12065 -0.2794)
			(end 0.12065 -0.3048)
			(stroke
				(width 0.1)
				(type default)
			)
			(layer "F.Fab")
		)
		(fp_line
			(start 0.12065 -0.3048)
			(end 0.67945 -0.3048)
			(stroke
				(width 0.1)
				(type default)
			)
			(layer "F.Fab")
		)
		(fp_line
			(start 0.120396 0.3048)
			(end 0.120396 0.2794)
			(stroke
				(width 0.1)
				(type default)
			)
			(layer "F.Fab")
		)
		(fp_line
			(start 0.120396 0.2794)
			(end -0.12065 0.2794)
			(stroke
				(width 0.1)
				(type default)
			)
			(layer "F.Fab")
		)
		(fp_line
			(start -0.12065 0.3048)
			(end -0.67945 0.3048)
			(stroke
				(width 0.1)
				(type default)
			)
			(layer "F.Fab")
		)
		(fp_line
			(start -0.12065 0.2794)
			(end -0.12065 0.3048)
			(stroke
				(width 0.1)
				(type default)
			)
			(layer "F.Fab")
		)
		(fp_line
			(start -0.12065 -0.2794)
			(end 0.12065 -0.2794)
			(stroke
				(width 0.1)
				(type default)
			)
			(layer "F.Fab")
		)
		(fp_line
			(start -0.12065 -0.305054)
			(end -0.12065 -0.2794)
			(stroke
				(width 0.1)
				(type default)
			)
			(layer "F.Fab")
		)
		(fp_line
			(start -0.67945 0.3048)
			(end -0.67945 -0.305054)
			(stroke
				(width 0.1)
				(type default)
			)
			(layer "F.Fab")
		)
		(fp_line
			(start -0.67945 -0.305054)
			(end -0.12065 -0.305054)
			(stroke
				(width 0.1)
				(type default)
			)
			(layer "F.Fab")
		)
		(pad "1" smd circle
			(at -0.40005 0 180)
			(size 0 0)
			(layers "F.Cu" "F.Mask" "F.Paste")
			(net "P3V3_AUX")
		)
		(pad "2" smd circle
			(at 0.40005 0 180)
			(size 0 0)
			(layers "F.Cu" "F.Mask" "F.Paste")
			(net "SMB_FRU_3V3AUX_SCL")
		)
	)
	(footprint ""
		(layer "F.Cu")
		(at 394.067284 -391.0584 180)
		(property "Reference" "R1101"
			(at 0 0 180)
			(layer "F.SilkS")
			(hide yes)
			(effects
				(font
					(size 1.27 1.27)
				)
			)
		)
		(property "Value" ""
			(at 0 0 180)
			(layer "F.Fab")
			(effects
				(font
					(size 1.27 1.27)
				)
			)
		)
		(duplicate_pad_numbers_are_jumpers no)
		(fp_line
			(start 0.32512 0.175006)
			(end -0.32512 0.175006)
			(stroke
				(width 0.1)
				(type default)
			)
			(layer "F.Fab")
		)
		(fp_line
			(start 0.32512 -0.175006)
			(end 0.32512 0.175006)
			(stroke
				(width 0.1)
				(type default)
			)
			(layer "F.Fab")
		)
		(fp_line
			(start -0.32512 0.175006)
			(end -0.32512 -0.175006)
			(stroke
				(width 0.1)
				(type default)
			)
			(layer "F.Fab")
		)
		(fp_line
			(start -0.32512 -0.175006)
			(end 0.32512 -0.175006)
			(stroke
				(width 0.1)
				(type default)
			)
			(layer "F.Fab")
		)
		(pad "1" smd rect
			(at -0.2667 0 180)
			(size 0.3048 0.381)
			(layers "F.Cu" "F.Mask" "F.Paste")
			(net "P1V8_CPU0_RT_1D")
		)
		(pad "2" smd rect
			(at 0.2667 0)
			(size 0.3048 0.381)
			(layers "F.Cu" "F.Mask" "F.Paste")
			(net "RT_CPU0_P3_ADDR1")
		)
	)
	(footprint ""
		(layer "F.Cu")
		(at 440.40171 -14.643354 180)
		(property "Reference" "C1236"
			(at 0 0 180)
			(layer "F.SilkS")
			(hide yes)
			(effects
				(font
					(size 1.27 1.27)
				)
			)
		)
		(property "Value" ""
			(at 0 0 180)
			(layer "F.Fab")
			(effects
				(font
					(size 1.27 1.27)
				)
			)
		)
		(duplicate_pad_numbers_are_jumpers no)
		(fp_line
			(start 0.7874 0.4064)
			(end -0.7874 0.4064)
			(stroke
				(width 0.1524)
				(type default)
			)
			(layer "F.SilkS")
		)
		(fp_line
			(start 0.7874 -0.4064)
			(end 0.7874 0.4064)
			(stroke
				(width 0.1524)
				(type default)
			)
			(layer "F.SilkS")
		)
		(fp_line
			(start -0.7874 0.4064)
			(end -0.7874 -0.4064)
			(stroke
				(width 0.1524)
				(type default)
			)
			(layer "F.SilkS")
		)
		(fp_line
			(start -0.7874 -0.4064)
			(end 0.7874 -0.4064)
			(stroke
				(width 0.1524)
				(type default)
			)
			(layer "F.SilkS")
		)
		(fp_line
			(start 0.67945 0.3048)
			(end 0.120396 0.3048)
			(stroke
				(width 0.1)
				(type default)
			)
			(layer "F.Fab")
		)
		(fp_line
			(start 0.67945 -0.3048)
			(end 0.67945 0.3048)
			(stroke
				(width 0.1)
				(type default)
			)
			(layer "F.Fab")
		)
		(fp_line
			(start 0.12065 -0.2794)
			(end 0.12065 -0.3048)
			(stroke
				(width 0.1)
				(type default)
			)
			(layer "F.Fab")
		)
		(fp_line
			(start 0.12065 -0.3048)
			(end 0.67945 -0.3048)
			(stroke
				(width 0.1)
				(type default)
			)
			(layer "F.Fab")
		)
		(fp_line
			(start 0.120396 0.3048)
			(end 0.120396 0.2794)
			(stroke
				(width 0.1)
				(type default)
			)
			(layer "F.Fab")
		)
		(fp_line
			(start 0.120396 0.2794)
			(end -0.12065 0.2794)
			(stroke
				(width 0.1)
				(type default)
			)
			(layer "F.Fab")
		)
		(fp_line
			(start -0.12065 0.3048)
			(end -0.67945 0.3048)
			(stroke
				(width 0.1)
				(type default)
			)
			(layer "F.Fab")
		)
		(fp_line
			(start -0.12065 0.2794)
			(end -0.12065 0.3048)
			(stroke
				(width 0.1)
				(type default)
			)
			(layer "F.Fab")
		)
		(fp_line
			(start -0.12065 -0.2794)
			(end 0.12065 -0.2794)
			(stroke
				(width 0.1)
				(type default)
			)
			(layer "F.Fab")
		)
		(fp_line
			(start -0.12065 -0.305054)
			(end -0.12065 -0.2794)
			(stroke
				(width 0.1)
				(type default)
			)
			(layer "F.Fab")
		)
		(fp_line
			(start -0.67945 0.3048)
			(end -0.67945 -0.305054)
			(stroke
				(width 0.1)
				(type default)
			)
			(layer "F.Fab")
		)
		(fp_line
			(start -0.67945 -0.305054)
			(end -0.12065 -0.305054)
			(stroke
				(width 0.1)
				(type default)
			)
			(layer "F.Fab")
		)
		(pad "1" smd circle
			(at -0.40005 0 180)
			(size 0 0)
			(layers "F.Cu" "F.Mask" "F.Paste")
			(net "P12V_OCP_SFF_R")
		)
		(pad "2" smd circle
			(at 0.40005 0 180)
			(size 0 0)
			(layers "F.Cu" "F.Mask" "F.Paste")
			(net "GND")
		)
	)
)
